(kicad_pcb
	(version 20241229)
	(generator "pcbnew")
	(generator_version "9.0")
	(general
		(thickness 1.62)
		(legacy_teardrops no)
	)
	(paper "A4")
	(title_block
		(title "OCuLink to 10GbE adapter")
		(date "2026-02-23")
		(rev "1.1.0")
		(company "Antmicro Ltd")
		(comment 1 "www.antmicro.com")
		(comment 9 "footprints 113-118 of 510")
	)
	(layers
		(0 "F.Cu" signal)
		(4 "In1.Cu" signal)
		(6 "In2.Cu" signal)
		(8 "In3.Cu" signal)
		(10 "In4.Cu" signal)
		(12 "In5.Cu" signal)
		(14 "In6.Cu" signal)
		(2 "B.Cu" signal)
		(9 "F.Adhes" user "F.Adhesive")
		(11 "B.Adhes" user "B.Adhesive")
		(13 "F.Paste" user)
		(15 "B.Paste" user)
		(5 "F.SilkS" user "F.Silkscreen")
		(7 "B.SilkS" user "B.Silkscreen")
		(1 "F.Mask" user)
		(3 "B.Mask" user)
		(17 "Dwgs.User" user "User.Drawings")
		(19 "Cmts.User" user "User.Comments")
		(21 "Eco1.User" user "User.Eco1")
		(23 "Eco2.User" user "User.Eco2")
		(25 "Edge.Cuts" user)
		(27 "Margin" user)
		(31 "F.CrtYd" user "F.Courtyard")
		(29 "B.CrtYd" user "B.Courtyard")
		(35 "F.Fab" user)
		(33 "B.Fab" user)
	)
	(footprint "antmicro-footprints:L_Bourns-SRP4021HMT"
		(layer "F.Cu")
		(at 60.249999 96.149999 180)
		(property "Reference" "L5"
			(at -3.950001 0.459999 0)
			(layer "F.SilkS")
			(effects
				(font
					(size 0.7 0.7)
					(thickness 0.15)
				)
				(justify right top)
			)
		)
		(property "Value" "L_1u_10A_Bourns-SRP4021HMT"
			(at -2.85 3.4 0)
			(layer "F.Fab")
			(hide yes)
			(effects
				(font
					(size 0.7 0.7)
					(thickness 0.15)
				)
				(justify right top)
			)
		)
		(property "Datasheet" "https://www.mouser.com/datasheet/2/54/Bourns_04_01_2025_SRP4021HMT_Datasheet-3580094.pdf"
			(at 0 0 0)
			(layer "F.Fab")
			(hide yes)
			(effects
				(font
					(size 0.7 0.7)
					(thickness 0.15)
				)
				(justify right top)
			)
		)
		(property "Description" "Power Inductors - SMD Ind,4.1x4.2x1.9mm,1uH+/-20%,10A, Shielded"
			(at 0 0 0)
			(layer "F.Fab")
			(hide yes)
			(effects
				(font
					(size 0.7 0.7)
					(thickness 0.15)
				)
				(justify right top)
			)
		)
		(property "Val" "1u/10A"
			(at 0 0 180)
			(unlocked yes)
			(layer "F.Fab")
			(hide yes)
			(effects
				(font
					(size 1 1)
					(thickness 0.15)
				)
			)
		)
		(property "Manufacturer" "Bourns"
			(at 0 0 180)
			(unlocked yes)
			(layer "F.Fab")
			(hide yes)
			(effects
				(font
					(size 1 1)
					(thickness 0.15)
				)
			)
		)
		(property "MPN" "SRP4021HMT-1R0M"
			(at 0 0 180)
			(unlocked yes)
			(layer "F.Fab")
			(hide yes)
			(effects
				(font
					(size 1 1)
					(thickness 0.15)
				)
			)
		)
		(property "ISat" ""
			(at 0 0 180)
			(unlocked yes)
			(layer "F.Fab")
			(hide yes)
			(effects
				(font
					(size 1 1)
					(thickness 0.15)
				)
			)
		)
		(property "Isat" "8A"
			(at 0 0 180)
			(unlocked yes)
			(layer "F.Fab")
			(hide yes)
			(effects
				(font
					(size 1 1)
					(thickness 0.15)
				)
			)
		)
		(property "IMax" ""
			(at 0 0 180)
			(unlocked yes)
			(layer "F.Fab")
			(hide yes)
			(effects
				(font
					(size 1 1)
					(thickness 0.15)
				)
			)
		)
		(property "Imax" "10A"
			(at 0 0 180)
			(unlocked yes)
			(layer "F.Fab")
			(hide yes)
			(effects
				(font
					(size 1 1)
					(thickness 0.15)
				)
			)
		)
		(property "Size" "4.2x4.1"
			(at 0 0 180)
			(unlocked yes)
			(layer "F.Fab")
			(hide yes)
			(effects
				(font
					(size 1 1)
					(thickness 0.15)
				)
			)
		)
		(property "Author" "Antmicro"
			(at 0 0 180)
			(unlocked yes)
			(layer "F.Fab")
			(hide yes)
			(effects
				(font
					(size 1 1)
					(thickness 0.15)
				)
			)
		)
		(property "License" "Apache-2.0"
			(at 0 0 180)
			(unlocked yes)
			(layer "F.Fab")
			(hide yes)
			(effects
				(font
					(size 1 1)
					(thickness 0.15)
				)
			)
		)
		(sheetname "/Power/")
		(sheetfile "power.kicad_sch")
		(attr smd)
		(fp_line
			(start -0.8 2.05)
			(end 0.8 2.05)
			(stroke
				(width 0.15)
				(type solid)
			)
			(layer "F.SilkS")
		)
		(fp_line
			(start -0.8 -2.05)
			(end 0.8 -2.05)
			(stroke
				(width 0.15)
				(type solid)
			)
			(layer "F.SilkS")
		)
		(fp_rect
			(start -2.85 -2.3)
			(end 2.85 2.3)
			(stroke
				(width 0.05)
				(type solid)
			)
			(fill no)
			(layer "F.CrtYd")
		)
		(fp_rect
			(start -2 -2.05)
			(end 2 2.05)
			(stroke
				(width 0.15)
				(type solid)
			)
			(fill no)
			(layer "F.Fab")
		)
		(pad "1" smd rect
			(at 1.85 0)
			(size 1.5 3.5)
			(layers "F.Cu" "F.Mask" "F.Paste")
			(net 336 "/Power/DVDD_SW")
			(pintype "passive")
		)
		(pad "2" smd rect
			(at -1.85 0)
			(size 1.5 3.5)
			(layers "F.Cu" "F.Mask" "F.Paste")
			(net 311 "/Power/+DVDD_OUT")
			(pintype "passive")
		)
	)
	(footprint "antmicro-footprints:TP_SMD_0.75mm"
		(layer "F.Cu")
		(at 52.05 126.200001 180)
		(property "Reference" "TP20"
			(at 0.24 0.07 180)
			(layer "F.SilkS")
			(hide yes)
			(effects
				(font
					(size 0.7 0.7)
					(thickness 0.15)
				)
				(justify right top)
			)
		)
		(property "Value" "TP_0.75mm_SMD"
			(at 0 1.2 0)
			(layer "F.Fab")
			(hide yes)
			(effects
				(font
					(size 0.7 0.7)
					(thickness 0.15)
				)
				(justify right top)
			)
		)
		(property "Description" "SMT test point"
			(at 0 0 0)
			(layer "F.Fab")
			(hide yes)
			(effects
				(font
					(size 1.27 1.27)
					(thickness 0.15)
				)
			)
		)
		(property "MPN" ""
			(at 0 0 180)
			(unlocked yes)
			(layer "F.Fab")
			(hide yes)
			(effects
				(font
					(size 1 1)
					(thickness 0.15)
				)
			)
		)
		(property "Manufacturer" ""
			(at 0 0 180)
			(unlocked yes)
			(layer "F.Fab")
			(hide yes)
			(effects
				(font
					(size 1 1)
					(thickness 0.15)
				)
			)
		)
		(property "Author" "Antmicro"
			(at 0 0 180)
			(unlocked yes)
			(layer "F.Fab")
			(hide yes)
			(effects
				(font
					(size 1 1)
					(thickness 0.15)
				)
			)
		)
		(property "License" "Apache-2.0"
			(at 0 0 180)
			(unlocked yes)
			(layer "F.Fab")
			(hide yes)
			(effects
				(font
					(size 1 1)
					(thickness 0.15)
				)
			)
		)
		(sheetname "/Power/")
		(sheetfile "power.kicad_sch")
		(attr exclude_from_pos_files exclude_from_bom)
		(fp_circle
			(center 0 0)
			(end 0.475 0)
			(stroke
				(width 0.05)
				(type default)
			)
			(fill no)
			(layer "F.CrtYd")
		)
		(pad "1" smd circle
			(at 0 0 180)
			(size 0.75 0.75)
			(layers "F.Cu" "F.Mask")
			(net 303 "/Power/+VCCD_OUT")
			(pinfunction "1")
			(pintype "passive")
		)
	)
	(footprint "antmicro-footprints:C_0603_1608Metric_EIA"
		(layer "F.Cu")
		(at 66.7 92.049999 180)
		(descr "Capacitor SMD 0603, IPC-7351 Density Level A")
		(tags "Capacitor 0603")
		(property "Reference" "C80"
			(at -3.22 -0.120001 0)
			(layer "F.SilkS")
			(effects
				(font
					(size 0.7 0.7)
					(thickness 0.15)
				)
				(justify right top)
			)
		)
		(property "Value" "C_22u_16V_0603"
			(at -1.42757 1.770288 0)
			(layer "F.Fab")
			(hide yes)
			(effects
				(font
					(size 0.7 0.7)
					(thickness 0.15)
				)
				(justify right top)
			)
		)
		(property "Datasheet" "https://product.samsungsem.com/mlcc/CL10A226MO7JZN.do"
			(at 0 0 0)
			(layer "F.Fab")
			(hide yes)
			(effects
				(font
					(size 1.27 1.27)
					(thickness 0.15)
				)
			)
		)
		(property "Description" "SMD Multilayer Ceramic Capacitor"
			(at 0 0 0)
			(layer "F.Fab")
			(hide yes)
			(effects
				(font
					(size 1.27 1.27)
					(thickness 0.15)
				)
			)
		)
		(property "MPN" "CL10A226MO7JZNC"
			(at 0 0 180)
			(unlocked yes)
			(layer "F.Fab")
			(hide yes)
			(effects
				(font
					(size 1 1)
					(thickness 0.15)
				)
			)
		)
		(property "Manufacturer" "Samsung Electro-Mechanics"
			(at 0 0 180)
			(unlocked yes)
			(layer "F.Fab")
			(hide yes)
			(effects
				(font
					(size 1 1)
					(thickness 0.15)
				)
			)
		)
		(property "License" "Apache-2.0"
			(at 0 0 180)
			(unlocked yes)
			(layer "F.Fab")
			(hide yes)
			(effects
				(font
					(size 1 1)
					(thickness 0.15)
				)
			)
		)
		(property "Author" "Antmicro"
			(at 0 0 180)
			(unlocked yes)
			(layer "F.Fab")
			(hide yes)
			(effects
				(font
					(size 1 1)
					(thickness 0.15)
				)
			)
		)
		(property "Val" "22u"
			(at 0 0 180)
			(unlocked yes)
			(layer "F.Fab")
			(hide yes)
			(effects
				(font
					(size 1 1)
					(thickness 0.15)
				)
			)
		)
		(property "Voltage" "16V"
			(at 0 0 180)
			(unlocked yes)
			(layer "F.Fab")
			(hide yes)
			(effects
				(font
					(size 1 1)
					(thickness 0.15)
				)
			)
		)
		(property "Dielectric" ""
			(at 0 0 180)
			(unlocked yes)
			(layer "F.Fab")
			(hide yes)
			(effects
				(font
					(size 1 1)
					(thickness 0.15)
				)
			)
		)
		(sheetname "/X710-AT2 power/")
		(sheetfile "x710-at2-power.kicad_sch")
		(attr smd)
		(fp_line
			(start -0.15 0.55)
			(end 0.15 0.55)
			(stroke
				(width 0.15)
				(type solid)
			)
			(layer "F.SilkS")
		)
		(fp_line
			(start -0.15 -0.55)
			(end 0.15 -0.55)
			(stroke
				(width 0.15)
				(type solid)
			)
			(layer "F.SilkS")
		)
		(fp_rect
			(start -1.25 -0.65)
			(end 1.25 0.65)
			(stroke
				(width 0.05)
				(type solid)
			)
			(fill no)
			(layer "F.CrtYd")
		)
		(fp_rect
			(start -0.8 -0.45)
			(end 0.8 0.45)
			(stroke
				(width 0.15)
				(type solid)
			)
			(fill no)
			(layer "F.Fab")
		)
		(pad "1" smd roundrect
			(at -0.7 0 180)
			(size 0.8 1.1)
			(layers "F.Cu" "F.Mask" "F.Paste")
			(roundrect_rratio 0.2)
			(net 28 "GND")
			(pintype "passive")
		)
		(pad "2" smd roundrect
			(at 0.7 0 180)
			(size 0.8 1.1)
			(layers "F.Cu" "F.Mask" "F.Paste")
			(roundrect_rratio 0.2)
			(net 6 "DVDD")
			(pintype "passive")
		)
	)
	(footprint "antmicro-footprints:C_0402_1005Metric"
		(layer "F.Cu")
		(at 56.399999 113.200001)
		(descr "Capacitor SMD 0402")
		(tags "capacitor SMD 0402")
		(property "Reference" "C28"
			(at -0.749999 1.349999 0)
			(layer "F.SilkS")
			(effects
				(font
					(size 0.7 0.7)
					(thickness 0.15)
				)
				(justify left bottom)
			)
		)
		(property "Value" "C_100n_0402"
			(at -1.022927 2.155213 0)
			(layer "F.Fab")
			(hide yes)
			(effects
				(font
					(size 0.7 0.7)
					(thickness 0.15)
				)
				(justify left bottom)
			)
		)
		(property "Datasheet" "https://www.murata.com/products/productdetail?partno=GRM155R61H104KE14%23"
			(at 0 0 0)
			(layer "F.Fab")
			(hide yes)
			(effects
				(font
					(size 1.27 1.27)
					(thickness 0.15)
				)
			)
		)
		(property "Description" "SMD Multilayer Ceramic Capacitor, 0.1 µF, 50 V, 0402 [1005 Metric], ± 10%, X5R, GRM Series"
			(at 0 0 0)
			(layer "F.Fab")
			(hide yes)
			(effects
				(font
					(size 1.27 1.27)
					(thickness 0.15)
				)
			)
		)
		(property "MPN" "GRM155R61H104KE14D"
			(at 0 0 0)
			(unlocked yes)
			(layer "F.Fab")
			(hide yes)
			(effects
				(font
					(size 1 1)
					(thickness 0.15)
				)
			)
		)
		(property "Manufacturer" "Murata"
			(at 0 0 0)
			(unlocked yes)
			(layer "F.Fab")
			(hide yes)
			(effects
				(font
					(size 1 1)
					(thickness 0.15)
				)
			)
		)
		(property "License" "Apache-2.0"
			(at 0 0 0)
			(unlocked yes)
			(layer "F.Fab")
			(hide yes)
			(effects
				(font
					(size 1 1)
					(thickness 0.15)
				)
			)
		)
		(property "Author" "Antmicro"
			(at 0 0 0)
			(unlocked yes)
			(layer "F.Fab")
			(hide yes)
			(effects
				(font
					(size 1 1)
					(thickness 0.15)
				)
			)
		)
		(property "Val" "100n"
			(at 0 0 0)
			(unlocked yes)
			(layer "F.Fab")
			(hide yes)
			(effects
				(font
					(size 1 1)
					(thickness 0.15)
				)
			)
		)
		(property "Voltage" "50V"
			(at 0 0 0)
			(unlocked yes)
			(layer "F.Fab")
			(hide yes)
			(effects
				(font
					(size 1 1)
					(thickness 0.15)
				)
			)
		)
		(property "Dielectric" "X5R"
			(at 0 0 0)
			(unlocked yes)
			(layer "F.Fab")
			(hide yes)
			(effects
				(font
					(size 1 1)
					(thickness 0.15)
				)
			)
		)
		(sheetname "/Power/")
		(sheetfile "power.kicad_sch")
		(attr smd)
		(fp_rect
			(start -0.925 -0.47)
			(end 0.925 0.47)
			(stroke
				(width 0.05)
				(type default)
			)
			(fill no)
			(layer "F.CrtYd")
		)
		(fp_line
			(start -0.494 -0.25)
			(end 0.504 -0.25)
			(stroke
				(width 0.15)
				(type solid)
			)
			(layer "F.Fab")
		)
		(fp_line
			(start -0.494 0.248)
			(end -0.494 -0.25)
			(stroke
				(width 0.15)
				(type solid)
			)
			(layer "F.Fab")
		)
		(fp_line
			(start 0.504 -0.25)
			(end 0.504 0.248)
			(stroke
				(width 0.15)
				(type solid)
			)
			(layer "F.Fab")
		)
		(fp_line
			(start 0.504 0.248)
			(end -0.494 0.248)
			(stroke
				(width 0.15)
				(type solid)
			)
			(layer "F.Fab")
		)
		(pad "1" smd roundrect
			(at -0.48 0)
			(size 0.59 0.64)
			(layers "F.Cu" "F.Mask" "F.Paste")
			(roundrect_rratio 0.25)
			(net 327 "/Power/1V0_BST")
			(pintype "passive")
		)
		(pad "2" smd roundrect
			(at 0.48 0)
			(size 0.59 0.64)
			(layers "F.Cu" "F.Mask" "F.Paste")
			(roundrect_rratio 0.25)
			(net 337 "/Power/1V0_SW")
			(pintype "passive")
		)
	)
	(footprint "antmicro-footprints:R_0402_1005Metric"
		(layer "F.Cu")
		(at 113.15 100.1 -90)
		(descr "Resistor SMD 0402")
		(tags "resistor SMD 0402")
		(property "Reference" "R178"
			(at -0.8 -0.45 90)
			(layer "F.SilkS")
			(effects
				(font
					(size 0.7 0.7)
					(thickness 0.15)
				)
				(justify left bottom)
			)
		)
		(property "Value" "R_1k_0402"
			(at -1.011843 1.772046 90)
			(layer "F.Fab")
			(hide yes)
			(effects
				(font
					(size 0.7 0.7)
					(thickness 0.15)
				)
				(justify right top)
			)
		)
		(property "Datasheet" "https://www.bourns.com/docs/product-datasheets/cr.pdf"
			(at 0 0 90)
			(layer "F.Fab")
			(hide yes)
			(effects
				(font
					(size 1.27 1.27)
					(thickness 0.15)
				)
			)
		)
		(property "Description" "SMD Chip Resistor, 1 kohm, ± 1%, 63 mW, 0402 [1005 Metric], Thick Film, General Purpose"
			(at 0 0 90)
			(layer "F.Fab")
			(hide yes)
			(effects
				(font
					(size 1.27 1.27)
					(thickness 0.15)
				)
			)
		)
		(property "MPN" "CR0402-FX-1001GLF"
			(at 0 0 270)
			(unlocked yes)
			(layer "F.Fab")
			(hide yes)
			(effects
				(font
					(size 1 1)
					(thickness 0.15)
				)
			)
		)
		(property "Manufacturer" "Bourns"
			(at 0 0 270)
			(unlocked yes)
			(layer "F.Fab")
			(hide yes)
			(effects
				(font
					(size 1 1)
					(thickness 0.15)
				)
			)
		)
		(property "License" "Apache-2.0"
			(at 0 0 270)
			(unlocked yes)
			(layer "F.Fab")
			(hide yes)
			(effects
				(font
					(size 1 1)
					(thickness 0.15)
				)
			)
		)
		(property "Author" "Antmicro"
			(at 0 0 270)
			(unlocked yes)
			(layer "F.Fab")
			(hide yes)
			(effects
				(font
					(size 1 1)
					(thickness 0.15)
				)
			)
		)
		(property "Val" "1k"
			(at 0 0 270)
			(unlocked yes)
			(layer "F.Fab")
			(hide yes)
			(effects
				(font
					(size 1 1)
					(thickness 0.15)
				)
			)
		)
		(property "Tolerance" "1%"
			(at 0 0 270)
			(unlocked yes)
			(layer "F.Fab")
			(hide yes)
			(effects
				(font
					(size 1 1)
					(thickness 0.15)
				)
			)
		)
		(sheetname "/Fan controller/")
		(sheetfile "fan-controller.kicad_sch")
		(attr smd exclude_from_pos_files exclude_from_bom dnp)
		(fp_rect
			(start -0.925 -0.47)
			(end 0.925 0.47)
			(stroke
				(width 0.05)
				(type default)
			)
			(fill no)
			(layer "F.CrtYd")
		)
		(fp_rect
			(start -0.5 -0.25)
			(end 0.5 0.25)
			(stroke
				(width 0.15)
				(type solid)
			)
			(fill no)
			(layer "F.Fab")
		)
		(pad "1" smd roundrect
			(at -0.48 0 270)
			(size 0.59 0.64)
			(layers "F.Cu" "F.Mask" "F.Paste")
			(roundrect_rratio 0.25)
			(net 28 "GND")
			(pintype "passive")
		)
		(pad "2" smd roundrect
			(at 0.48 0 270)
			(size 0.59 0.64)
			(layers "F.Cu" "F.Mask" "F.Paste")
			(roundrect_rratio 0.25)
			(net 399 "/Fan controller/DMIN")
			(pintype "passive")
		)
	)
	(footprint "antmicro-footprints:R_0402_1005Metric"
		(layer "F.Cu")
		(at 116.95 107.5 180)
		(descr "Resistor SMD 0402")
		(tags "resistor SMD 0402")
		(property "Reference" "R174"
			(at 0.85 0.35 0)
			(layer "F.SilkS")
			(effects
				(font
					(size 0.7 0.7)
					(thickness 0.15)
				)
				(justify right top)
			)
		)
		(property "Value" "R_0R_0402"
			(at -1.011843 1.772046 0)
			(layer "F.Fab")
			(hide yes)
			(effects
				(font
					(size 0.7 0.7)
					(thickness 0.15)
				)
				(justify right top)
			)
		)
		(property "Datasheet" "https://industrial.panasonic.com/cdbs/www-data/pdf/RDA0000/AOA0000C301.pdf"
			(at 0 0 0)
			(layer "F.Fab")
			(hide yes)
			(effects
				(font
					(size 1.27 1.27)
					(thickness 0.15)
				)
			)
		)
		(property "Description" "SMD Chip Resistor, Jumper, 0 ohm, 100 mW, 0402 [1005 Metric], Thick Film, General Purpose"
			(at 0 0 0)
			(layer "F.Fab")
			(hide yes)
			(effects
				(font
					(size 1.27 1.27)
					(thickness 0.15)
				)
			)
		)
		(property "MPN" "ERJ2GE0R00X"
			(at 0 0 180)
			(unlocked yes)
			(layer "F.Fab")
			(hide yes)
			(effects
				(font
					(size 1 1)
					(thickness 0.15)
				)
			)
		)
		(property "Manufacturer" "Panasonic"
			(at 0 0 180)
			(unlocked yes)
			(layer "F.Fab")
			(hide yes)
			(effects
				(font
					(size 1 1)
					(thickness 0.15)
				)
			)
		)
		(property "License" "Apache-2.0"
			(at 0 0 180)
			(unlocked yes)
			(layer "F.Fab")
			(hide yes)
			(effects
				(font
					(size 1 1)
					(thickness 0.15)
				)
			)
		)
		(property "Author" "Antmicro"
			(at 0 0 180)
			(unlocked yes)
			(layer "F.Fab")
			(hide yes)
			(effects
				(font
					(size 1 1)
					(thickness 0.15)
				)
			)
		)
		(property "Val" "0R"
			(at 0 0 180)
			(unlocked yes)
			(layer "F.Fab")
			(hide yes)
			(effects
				(font
					(size 1 1)
					(thickness 0.15)
				)
			)
		)
		(property "Tolerance" "~"
			(at 0 0 180)
			(unlocked yes)
			(layer "F.Fab")
			(hide yes)
			(effects
				(font
					(size 1 1)
					(thickness 0.15)
				)
			)
		)
		(property "Current" "1A"
			(at 0 0 180)
			(unlocked yes)
			(layer "F.Fab")
			(hide yes)
			(effects
				(font
					(size 1 1)
					(thickness 0.15)
				)
			)
		)
		(sheetname "/Fan controller/")
		(sheetfile "fan-controller.kicad_sch")
		(attr smd exclude_from_pos_files exclude_from_bom dnp)
		(fp_rect
			(start -0.925 -0.47)
			(end 0.925 0.47)
			(stroke
				(width 0.05)
				(type default)
			)
			(fill no)
			(layer "F.CrtYd")
		)
		(fp_rect
			(start -0.5 -0.25)
			(end 0.5 0.25)
			(stroke
				(width 0.15)
				(type solid)
			)
			(fill no)
			(layer "F.Fab")
		)
		(pad "1" smd roundrect
			(at -0.48 0 180)
			(size 0.59 0.64)
			(layers "F.Cu" "F.Mask" "F.Paste")
			(roundrect_rratio 0.25)
			(net 389 "/Fan controller/V_{FAN}")
			(pintype "passive")
		)
		(pad "2" smd roundrect
			(at 0.48 0 180)
			(size 0.59 0.64)
			(layers "F.Cu" "F.Mask" "F.Paste")
			(roundrect_rratio 0.25)
			(net 388 "/Fan controller/+5V")
			(pintype "passive")
		)
	)
)
